FILE_TYPE = MACRO_DRAWING;
SET COLOR_WIRE YELLOW;
SET COLOR_PROP ORANGE;
SET COLOR_DOT WHITE;
SET COLOR_ARC YELLOW;
SET COLOR_BODY GREEN;
SET COLOR_NOTE PURPLE;
SET PROP_DISPLAY VALUE;
SET PAGE_NUMBER P70;
FORCEADD Q_CAP..1
(-8600 3100);
FORCEPROP 1 LAST LOCATION C2514
J 0
(-8550 3200);
DISPLAY 0.489362 (-8550 3200);
PAINT SKYBLUE (-8550 3200);
FORCEPROP 2 LAST $SEC 1
J 0
(-8550 3300);
DISPLAY 0.680851 (-8550 3300);
PAINT MONO (-8550 3300);
DISPLAY INVISIBLE (-8550 3300);
FORCEPROP 2 LAST CDS_SEC 1
J 0
(-8550 3300);
DISPLAY 1.021277 (-8550 3300);
DISPLAY INVISIBLE (-8550 3300);
FORCEPROP 1 LASTPIN (-8600 3200) $PN 1
J 0
(-8590 3180);
DISPLAY 0.489362 (-8590 3180);
FORCEPROP 1 LASTPIN (-8600 3000) $PN 2
J 0
(-8590 2980);
DISPLAY 0.489362 (-8590 2980);
FORCEPROP 1 LAST PACK_TYPE C0402
J 0
(-8550 2900);
DISPLAY 0.489362 (-8550 2900);
PAINT SKYBLUE (-8550 2900);
FORCEPROP 1 LAST VOLTAGE 4V
J 0
(-8550 3100);
DISPLAY 0.489362 (-8550 3100);
PAINT SKYBLUE (-8550 3100);
FORCEPROP 1 LAST VALUE 22UF
J 0
(-8550 3150);
DISPLAY 0.489362 (-8550 3150);
PAINT SKYBLUE (-8550 3150);
FORCEPROP 1 LAST TOLERANCE 20%
J 0
(-8550 3050);
DISPLAY 0.489362 (-8550 3050);
PAINT SKYBLUE (-8550 3050);
FORCEPROP 1 LAST MATERIAL X6S
J 0
(-8550 3000);
DISPLAY 0.489362 (-8550 3000);
PAINT SKYBLUE (-8550 3000);
FORCEPROP 2 LAST CDS_LIB pure_quanta
J 0
(-8600 3100);
PAINT MONO (-8600 3100);
DISPLAY INVISIBLE (-8600 3100);
FORCEPROP 1 LAST PATH I1
J 0
(-8550 3250);
DISPLAY 0.978723 (-8550 3250);
PAINT WHITE (-8550 3250);
DISPLAY INVISIBLE (-8550 3250);
FORCEPROP 1 LAST PART_NUMBER CH622KMEB02
J 0
(-8550 2950);
DISPLAY 0.489362 (-8550 2950);
PAINT SKYBLUE (-8550 2950);
DISPLAY INVISIBLE (-8550 2950);
FORCEADD Q_CAP..1
(-7700 3875);
FORCEPROP 1 LAST LOCATION C2518
J 0
(-7650 3975);
DISPLAY 0.489362 (-7650 3975);
PAINT SKYBLUE (-7650 3975);
FORCEPROP 2 LAST $SEC 1
J 0
(-7650 4075);
DISPLAY 0.680851 (-7650 4075);
PAINT MONO (-7650 4075);
DISPLAY INVISIBLE (-7650 4075);
FORCEPROP 2 LAST CDS_SEC 1
J 0
(-7650 4075);
DISPLAY 1.021277 (-7650 4075);
DISPLAY INVISIBLE (-7650 4075);
FORCEPROP 1 LASTPIN (-7700 3975) $PN 1
J 0
(-7690 3955);
DISPLAY 0.489362 (-7690 3955);
FORCEPROP 1 LASTPIN (-7700 3775) $PN 2
J 0
(-7690 3755);
DISPLAY 0.489362 (-7690 3755);
FORCEPROP 1 LAST PACK_TYPE C0402
J 0
(-7650 3675);
DISPLAY 0.489362 (-7650 3675);
PAINT SKYBLUE (-7650 3675);
FORCEPROP 1 LAST VOLTAGE 4V
J 0
(-7650 3875);
DISPLAY 0.489362 (-7650 3875);
PAINT SKYBLUE (-7650 3875);
FORCEPROP 1 LAST VALUE 22UF
J 0
(-7650 3925);
DISPLAY 0.489362 (-7650 3925);
PAINT SKYBLUE (-7650 3925);
FORCEPROP 1 LAST TOLERANCE 20%
J 0
(-7650 3825);
DISPLAY 0.489362 (-7650 3825);
PAINT SKYBLUE (-7650 3825);
FORCEPROP 1 LAST MATERIAL X6S
J 0
(-7650 3775);
DISPLAY 0.489362 (-7650 3775);
PAINT SKYBLUE (-7650 3775);
FORCEPROP 2 LAST CDS_LIB pure_quanta
J 0
(-7700 3875);
PAINT MONO (-7700 3875);
DISPLAY INVISIBLE (-7700 3875);
FORCEPROP 1 LAST PATH I10
J 0
(-7650 4025);
DISPLAY 0.978723 (-7650 4025);
PAINT WHITE (-7650 4025);
DISPLAY INVISIBLE (-7650 4025);
FORCEPROP 1 LAST PART_NUMBER CH622KMEB02
J 0
(-7650 3725);
DISPLAY 0.489362 (-7650 3725);
PAINT SKYBLUE (-7650 3725);
DISPLAY INVISIBLE (-7650 3725);
FORCEADD Q_CAP..1
(-7250 3875);
FORCEPROP 1 LAST LOCATION C2520
J 0
(-7200 3975);
DISPLAY 0.489362 (-7200 3975);
PAINT SKYBLUE (-7200 3975);
FORCEPROP 2 LAST $SEC 1
J 0
(-7200 4075);
DISPLAY 0.680851 (-7200 4075);
PAINT MONO (-7200 4075);
DISPLAY INVISIBLE (-7200 4075);
FORCEPROP 2 LAST CDS_SEC 1
J 0
(-7200 4075);
DISPLAY 1.021277 (-7200 4075);
DISPLAY INVISIBLE (-7200 4075);
FORCEPROP 1 LASTPIN (-7250 3975) $PN 1
J 0
(-7240 3955);
DISPLAY 0.489362 (-7240 3955);
FORCEPROP 1 LASTPIN (-7250 3775) $PN 2
J 0
(-7240 3755);
DISPLAY 0.489362 (-7240 3755);
FORCEPROP 1 LAST PACK_TYPE C0402
J 0
(-7200 3675);
DISPLAY 0.489362 (-7200 3675);
PAINT SKYBLUE (-7200 3675);
FORCEPROP 1 LAST VOLTAGE 4V
J 0
(-7200 3875);
DISPLAY 0.489362 (-7200 3875);
PAINT SKYBLUE (-7200 3875);
FORCEPROP 1 LAST VALUE 22UF
J 0
(-7200 3925);
DISPLAY 0.489362 (-7200 3925);
PAINT SKYBLUE (-7200 3925);
FORCEPROP 1 LAST TOLERANCE 20%
J 0
(-7200 3825);
DISPLAY 0.489362 (-7200 3825);
PAINT SKYBLUE (-7200 3825);
FORCEPROP 1 LAST MATERIAL X6S
J 0
(-7200 3775);
DISPLAY 0.489362 (-7200 3775);
PAINT SKYBLUE (-7200 3775);
FORCEPROP 2 LAST CDS_LIB pure_quanta
J 0
(-7250 3875);
PAINT MONO (-7250 3875);
DISPLAY INVISIBLE (-7250 3875);
FORCEPROP 1 LAST PATH I11
J 0
(-7200 4025);
DISPLAY 0.978723 (-7200 4025);
PAINT WHITE (-7200 4025);
DISPLAY INVISIBLE (-7200 4025);
FORCEPROP 1 LAST PART_NUMBER CH622KMEB02
J 0
(-7200 3725);
DISPLAY 0.489362 (-7200 3725);
PAINT SKYBLUE (-7200 3725);
DISPLAY INVISIBLE (-7200 3725);
FORCEADD Q_CAP..1
(-6800 3875);
FORCEPROP 1 LAST LOCATION C2521
J 0
(-6750 3975);
DISPLAY 0.489362 (-6750 3975);
PAINT SKYBLUE (-6750 3975);
FORCEPROP 2 LAST $SEC 1
J 0
(-6750 4075);
DISPLAY 0.680851 (-6750 4075);
PAINT MONO (-6750 4075);
DISPLAY INVISIBLE (-6750 4075);
FORCEPROP 2 LAST CDS_SEC 1
J 0
(-6750 4075);
DISPLAY 1.021277 (-6750 4075);
DISPLAY INVISIBLE (-6750 4075);
FORCEPROP 1 LASTPIN (-6800 3975) $PN 1
J 0
(-6790 3955);
DISPLAY 0.489362 (-6790 3955);
FORCEPROP 1 LASTPIN (-6800 3775) $PN 2
J 0
(-6790 3755);
DISPLAY 0.489362 (-6790 3755);
FORCEPROP 1 LAST PACK_TYPE C0402
J 0
(-6750 3675);
DISPLAY 0.489362 (-6750 3675);
PAINT SKYBLUE (-6750 3675);
FORCEPROP 1 LAST VOLTAGE 4V
J 0
(-6750 3875);
DISPLAY 0.489362 (-6750 3875);
PAINT SKYBLUE (-6750 3875);
FORCEPROP 1 LAST VALUE 22UF
J 0
(-6750 3925);
DISPLAY 0.489362 (-6750 3925);
PAINT SKYBLUE (-6750 3925);
FORCEPROP 1 LAST TOLERANCE 20%
J 0
(-6750 3825);
DISPLAY 0.489362 (-6750 3825);
PAINT SKYBLUE (-6750 3825);
FORCEPROP 1 LAST MATERIAL X6S
J 0
(-6750 3775);
DISPLAY 0.489362 (-6750 3775);
PAINT SKYBLUE (-6750 3775);
FORCEPROP 2 LAST CDS_LIB pure_quanta
J 0
(-6800 3875);
PAINT MONO (-6800 3875);
DISPLAY INVISIBLE (-6800 3875);
FORCEPROP 1 LAST PATH I12
J 0
(-6750 4025);
DISPLAY 0.978723 (-6750 4025);
PAINT WHITE (-6750 4025);
DISPLAY INVISIBLE (-6750 4025);
FORCEPROP 1 LAST PART_NUMBER CH622KMEB02
J 0
(-6750 3725);
DISPLAY 0.489362 (-6750 3725);
PAINT SKYBLUE (-6750 3725);
DISPLAY INVISIBLE (-6750 3725);
FORCEADD Q_CAP..1
(-6350 3875);
FORCEPROP 1 LAST LOCATION C2522
J 0
(-6300 3975);
DISPLAY 0.489362 (-6300 3975);
PAINT SKYBLUE (-6300 3975);
FORCEPROP 2 LAST $SEC 1
J 0
(-6300 4075);
DISPLAY 0.680851 (-6300 4075);
PAINT MONO (-6300 4075);
DISPLAY INVISIBLE (-6300 4075);
FORCEPROP 2 LAST CDS_SEC 1
J 0
(-6300 4075);
DISPLAY 1.021277 (-6300 4075);
DISPLAY INVISIBLE (-6300 4075);
FORCEPROP 1 LASTPIN (-6350 3975) $PN 1
J 0
(-6340 3955);
DISPLAY 0.489362 (-6340 3955);
FORCEPROP 1 LASTPIN (-6350 3775) $PN 2
J 0
(-6340 3755);
DISPLAY 0.489362 (-6340 3755);
FORCEPROP 1 LAST PACK_TYPE C0402
J 0
(-6300 3675);
DISPLAY 0.489362 (-6300 3675);
PAINT SKYBLUE (-6300 3675);
FORCEPROP 1 LAST VOLTAGE 4V
J 0
(-6300 3875);
DISPLAY 0.489362 (-6300 3875);
PAINT SKYBLUE (-6300 3875);
FORCEPROP 1 LAST VALUE 22UF
J 0
(-6300 3925);
DISPLAY 0.489362 (-6300 3925);
PAINT SKYBLUE (-6300 3925);
FORCEPROP 1 LAST TOLERANCE 20%
J 0
(-6300 3825);
DISPLAY 0.489362 (-6300 3825);
PAINT SKYBLUE (-6300 3825);
FORCEPROP 1 LAST MATERIAL X6S
J 0
(-6300 3775);
DISPLAY 0.489362 (-6300 3775);
PAINT SKYBLUE (-6300 3775);
FORCEPROP 2 LAST CDS_LIB pure_quanta
J 0
(-6350 3875);
PAINT MONO (-6350 3875);
DISPLAY INVISIBLE (-6350 3875);
FORCEPROP 1 LAST PATH I13
J 0
(-6300 4025);
DISPLAY 0.978723 (-6300 4025);
PAINT WHITE (-6300 4025);
DISPLAY INVISIBLE (-6300 4025);
FORCEPROP 1 LAST PART_NUMBER CH622KMEB02
J 0
(-6300 3725);
DISPLAY 0.489362 (-6300 3725);
PAINT SKYBLUE (-6300 3725);
DISPLAY INVISIBLE (-6300 3725);
FORCEADD Q_CAP..1
(-5900 3875);
FORCEPROP 1 LAST LOCATION C2523
J 0
(-5850 3975);
DISPLAY 0.489362 (-5850 3975);
PAINT SKYBLUE (-5850 3975);
FORCEPROP 2 LAST $SEC 1
J 0
(-5850 4075);
DISPLAY 0.680851 (-5850 4075);
PAINT MONO (-5850 4075);
DISPLAY INVISIBLE (-5850 4075);
FORCEPROP 2 LAST CDS_SEC 1
J 0
(-5850 4075);
DISPLAY 1.021277 (-5850 4075);
DISPLAY INVISIBLE (-5850 4075);
FORCEPROP 1 LASTPIN (-5900 3975) $PN 1
J 0
(-5890 3955);
DISPLAY 0.489362 (-5890 3955);
FORCEPROP 1 LASTPIN (-5900 3775) $PN 2
J 0
(-5890 3755);
DISPLAY 0.489362 (-5890 3755);
FORCEPROP 1 LAST PACK_TYPE C0402
J 0
(-5850 3675);
DISPLAY 0.489362 (-5850 3675);
PAINT SKYBLUE (-5850 3675);
FORCEPROP 1 LAST VOLTAGE 4V
J 0
(-5850 3875);
DISPLAY 0.489362 (-5850 3875);
PAINT SKYBLUE (-5850 3875);
FORCEPROP 1 LAST VALUE 22UF
J 0
(-5850 3925);
DISPLAY 0.489362 (-5850 3925);
PAINT SKYBLUE (-5850 3925);
FORCEPROP 1 LAST TOLERANCE 20%
J 0
(-5850 3825);
DISPLAY 0.489362 (-5850 3825);
PAINT SKYBLUE (-5850 3825);
FORCEPROP 1 LAST MATERIAL X6S
J 0
(-5850 3775);
DISPLAY 0.489362 (-5850 3775);
PAINT SKYBLUE (-5850 3775);
FORCEPROP 2 LAST CDS_LIB pure_quanta
J 0
(-5900 3875);
PAINT MONO (-5900 3875);
DISPLAY INVISIBLE (-5900 3875);
FORCEPROP 1 LAST PATH I14
J 0
(-5850 4025);
DISPLAY 0.978723 (-5850 4025);
PAINT WHITE (-5850 4025);
DISPLAY INVISIBLE (-5850 4025);
FORCEPROP 1 LAST PART_NUMBER CH622KMEB02
J 0
(-5850 3725);
DISPLAY 0.489362 (-5850 3725);
PAINT SKYBLUE (-5850 3725);
DISPLAY INVISIBLE (-5850 3725);
FORCEADD Q_CAP..1
(-5450 3875);
FORCEPROP 1 LAST LOCATION C2524
J 0
(-5400 3975);
DISPLAY 0.489362 (-5400 3975);
PAINT SKYBLUE (-5400 3975);
FORCEPROP 2 LAST $SEC 1
J 0
(-5400 4075);
DISPLAY 0.680851 (-5400 4075);
PAINT MONO (-5400 4075);
DISPLAY INVISIBLE (-5400 4075);
FORCEPROP 2 LAST CDS_SEC 1
J 0
(-5400 4075);
DISPLAY 1.021277 (-5400 4075);
DISPLAY INVISIBLE (-5400 4075);
FORCEPROP 1 LASTPIN (-5450 3975) $PN 1
J 0
(-5440 3955);
DISPLAY 0.489362 (-5440 3955);
FORCEPROP 1 LASTPIN (-5450 3775) $PN 2
J 0
(-5440 3755);
DISPLAY 0.489362 (-5440 3755);
FORCEPROP 1 LAST PACK_TYPE C0402
J 0
(-5400 3675);
DISPLAY 0.489362 (-5400 3675);
PAINT SKYBLUE (-5400 3675);
FORCEPROP 1 LAST VOLTAGE 4V
J 0
(-5400 3875);
DISPLAY 0.489362 (-5400 3875);
PAINT SKYBLUE (-5400 3875);
FORCEPROP 1 LAST VALUE 22UF
J 0
(-5400 3925);
DISPLAY 0.489362 (-5400 3925);
PAINT SKYBLUE (-5400 3925);
FORCEPROP 1 LAST TOLERANCE 20%
J 0
(-5400 3825);
DISPLAY 0.489362 (-5400 3825);
PAINT SKYBLUE (-5400 3825);
FORCEPROP 1 LAST MATERIAL X6S
J 0
(-5400 3775);
DISPLAY 0.489362 (-5400 3775);
PAINT SKYBLUE (-5400 3775);
FORCEPROP 2 LAST CDS_LIB pure_quanta
J 0
(-5450 3875);
PAINT MONO (-5450 3875);
DISPLAY INVISIBLE (-5450 3875);
FORCEPROP 1 LAST PATH I15
J 0
(-5400 4025);
DISPLAY 0.978723 (-5400 4025);
PAINT WHITE (-5400 4025);
DISPLAY INVISIBLE (-5400 4025);
FORCEPROP 1 LAST PART_NUMBER CH622KMEB02
J 0
(-5400 3725);
DISPLAY 0.489362 (-5400 3725);
PAINT SKYBLUE (-5400 3725);
DISPLAY INVISIBLE (-5400 3725);
FORCEADD Q_CAP..1
(-5000 3875);
FORCEPROP 1 LAST LOCATION C2525
J 0
(-4950 3975);
DISPLAY 0.489362 (-4950 3975);
PAINT SKYBLUE (-4950 3975);
FORCEPROP 2 LAST $SEC 1
J 0
(-4950 4075);
DISPLAY 0.680851 (-4950 4075);
PAINT MONO (-4950 4075);
DISPLAY INVISIBLE (-4950 4075);
FORCEPROP 2 LAST CDS_SEC 1
J 0
(-4950 4075);
DISPLAY 1.021277 (-4950 4075);
DISPLAY INVISIBLE (-4950 4075);
FORCEPROP 1 LASTPIN (-5000 3975) $PN 1
J 0
(-4990 3955);
DISPLAY 0.489362 (-4990 3955);
FORCEPROP 1 LASTPIN (-5000 3775) $PN 2
J 0
(-4990 3755);
DISPLAY 0.489362 (-4990 3755);
FORCEPROP 1 LAST PACK_TYPE C0402
J 0
(-4950 3675);
DISPLAY 0.489362 (-4950 3675);
PAINT SKYBLUE (-4950 3675);
FORCEPROP 1 LAST VOLTAGE 4V
J 0
(-4950 3875);
DISPLAY 0.489362 (-4950 3875);
PAINT SKYBLUE (-4950 3875);
FORCEPROP 1 LAST VALUE 22UF
J 0
(-4950 3925);
DISPLAY 0.489362 (-4950 3925);
PAINT SKYBLUE (-4950 3925);
FORCEPROP 1 LAST TOLERANCE 20%
J 0
(-4950 3825);
DISPLAY 0.489362 (-4950 3825);
PAINT SKYBLUE (-4950 3825);
FORCEPROP 1 LAST MATERIAL X6S
J 0
(-4950 3775);
DISPLAY 0.489362 (-4950 3775);
PAINT SKYBLUE (-4950 3775);
FORCEPROP 2 LAST CDS_LIB pure_quanta
J 0
(-5000 3875);
PAINT MONO (-5000 3875);
DISPLAY INVISIBLE (-5000 3875);
FORCEPROP 1 LAST PATH I16
J 0
(-4950 4025);
DISPLAY 0.978723 (-4950 4025);
PAINT WHITE (-4950 4025);
DISPLAY INVISIBLE (-4950 4025);
FORCEPROP 1 LAST PART_NUMBER CH622KMEB02
J 0
(-4950 3725);
DISPLAY 0.489362 (-4950 3725);
PAINT SKYBLUE (-4950 3725);
DISPLAY INVISIBLE (-4950 3725);
FORCEADD UNIVERSAL_GND..1
(-4600 3500);
FORCEPROP 3 LASTPIN (-4600 3550) SIG_NAME GND\g
J 0
(-4590 3560);
DISPLAY 0.659574 (-4590 3560);
PAINT MONO (-4590 3560);
DISPLAY INVISIBLE (-4590 3560);
FORCEPROP 2 LAST CDS_LIB pure_quanta_power
J 0
(-4600 3500);
PAINT MONO (-4600 3500);
DISPLAY INVISIBLE (-4600 3500);
FORCEPROP 1 LAST HDL_POWER GND
J 1
(-4575 3425);
DISPLAY 0.872340 (-4575 3425);
PAINT GREEN (-4575 3425);
DISPLAY INVISIBLE (-4575 3425);
FORCEPROP 1 LAST PATH I17
J 0
(-4525 3500);
DISPLAY 0.872340 (-4525 3500);
PAINT AQUA (-4525 3500);
DISPLAY INVISIBLE (-4525 3500);
FORCEADD Q_CAP..1
(-4600 3875);
FORCEPROP 1 LAST LOCATION C2526
J 0
(-4550 3975);
DISPLAY 0.489362 (-4550 3975);
PAINT SKYBLUE (-4550 3975);
FORCEPROP 2 LAST $SEC 1
J 0
(-4550 4075);
DISPLAY 0.680851 (-4550 4075);
PAINT MONO (-4550 4075);
DISPLAY INVISIBLE (-4550 4075);
FORCEPROP 2 LAST CDS_SEC 1
J 0
(-4550 4075);
DISPLAY 1.021277 (-4550 4075);
DISPLAY INVISIBLE (-4550 4075);
FORCEPROP 1 LASTPIN (-4600 3975) $PN 1
J 0
(-4590 3955);
DISPLAY 0.489362 (-4590 3955);
FORCEPROP 1 LASTPIN (-4600 3775) $PN 2
J 0
(-4590 3755);
DISPLAY 0.489362 (-4590 3755);
FORCEPROP 1 LAST PACK_TYPE C0402
J 0
(-4550 3675);
DISPLAY 0.489362 (-4550 3675);
PAINT SKYBLUE (-4550 3675);
FORCEPROP 1 LAST VOLTAGE 4V
J 0
(-4550 3875);
DISPLAY 0.489362 (-4550 3875);
PAINT SKYBLUE (-4550 3875);
FORCEPROP 1 LAST VALUE 22UF
J 0
(-4550 3925);
DISPLAY 0.489362 (-4550 3925);
PAINT SKYBLUE (-4550 3925);
FORCEPROP 1 LAST TOLERANCE 20%
J 0
(-4550 3825);
DISPLAY 0.489362 (-4550 3825);
PAINT SKYBLUE (-4550 3825);
FORCEPROP 1 LAST MATERIAL X6S
J 0
(-4550 3775);
DISPLAY 0.489362 (-4550 3775);
PAINT SKYBLUE (-4550 3775);
FORCEPROP 2 LAST CDS_LIB pure_quanta
J 0
(-4600 3875);
PAINT MONO (-4600 3875);
DISPLAY INVISIBLE (-4600 3875);
FORCEPROP 1 LAST PATH I18
J 0
(-4550 4025);
DISPLAY 0.978723 (-4550 4025);
PAINT WHITE (-4550 4025);
DISPLAY INVISIBLE (-4550 4025);
FORCEPROP 1 LAST PART_NUMBER CH622KMEB02
J 0
(-4550 3725);
DISPLAY 0.489362 (-4550 3725);
PAINT SKYBLUE (-4550 3725);
DISPLAY INVISIBLE (-4550 3725);
FORCEADD UNIVERSAL_POWER..1
(-8600 3375);
FORCEPROP 3 LASTPIN (-8600 3325) SIG_NAME PVDD18_S5_P0\g
J 0
(-8590 3335);
DISPLAY 0.659574 (-8590 3335);
PAINT MONO (-8590 3335);
DISPLAY INVISIBLE (-8590 3335);
FORCEPROP 1 LAST HDL_POWER PVDD18_S5_P0
J 1
(-8600 3425);
DISPLAY 0.489362 (-8600 3425);
PAINT GREEN (-8600 3425);
FORCEPROP 2 LAST CDS_LIB pure_quanta_power
J 0
(-8600 3375);
DISPLAY INVISIBLE (-8600 3375);
FORCEPROP 1 LAST PATH I2
J 0
(-8550 3400);
DISPLAY 0.872340 (-8550 3400);
PAINT AQUA (-8550 3400);
DISPLAY INVISIBLE (-8550 3400);
FORCEADD UNIVERSAL_POWER..1
(-8525 5800);
FORCEPROP 3 LASTPIN (-8525 5750) SIG_NAME PVDD_33_S5\g
J 0
(-8515 5760);
DISPLAY 0.659574 (-8515 5760);
PAINT MONO (-8515 5760);
DISPLAY INVISIBLE (-8515 5760);
FORCEPROP 1 LAST HDL_POWER PVDD_33_S5
J 1
(-8525 5850);
DISPLAY 0.489362 (-8525 5850);
PAINT GREEN (-8525 5850);
FORCEPROP 2 LAST CDS_LIB pure_quanta_power
J 0
(-8525 5800);
DISPLAY INVISIBLE (-8525 5800);
FORCEPROP 1 LAST PATH I23
J 0
(-8475 5825);
DISPLAY 0.872340 (-8475 5825);
PAINT AQUA (-8475 5825);
DISPLAY INVISIBLE (-8475 5825);
FORCEADD UNIVERSAL_GND..1
(-8075 5150);
FORCEPROP 3 LASTPIN (-8075 5200) SIG_NAME GND\g
J 0
(-8065 5210);
DISPLAY 0.659574 (-8065 5210);
PAINT MONO (-8065 5210);
DISPLAY INVISIBLE (-8065 5210);
FORCEPROP 2 LAST CDS_LIB pure_quanta_power
J 0
(-8075 5150);
PAINT MONO (-8075 5150);
DISPLAY INVISIBLE (-8075 5150);
FORCEPROP 1 LAST HDL_POWER GND
J 1
(-8050 5075);
DISPLAY 0.872340 (-8050 5075);
PAINT GREEN (-8050 5075);
DISPLAY INVISIBLE (-8050 5075);
FORCEPROP 1 LAST PATH I24
J 0
(-8000 5150);
DISPLAY 0.872340 (-8000 5150);
PAINT AQUA (-8000 5150);
DISPLAY INVISIBLE (-8000 5150);
FORCEADD Q_CAP..1
(-8075 5525);
FORCEPROP 1 LAST LOCATION C2515
J 0
(-8025 5625);
DISPLAY 0.638298 (-8025 5625);
FORCEPROP 0 LAST $SEC 1
J 0
(-8025 5675);
DISPLAY 0.680851 (-8025 5675);
PAINT MONO (-8025 5675);
DISPLAY INVISIBLE (-8025 5675);
FORCEPROP 0 LAST CDS_SEC 1
J 0
(-8025 5675);
DISPLAY 0.680851 (-8025 5675);
DISPLAY INVISIBLE (-8025 5675);
FORCEPROP 1 LASTPIN (-8075 5625) $PN 1
J 0
(-8065 5605);
DISPLAY 0.787234 (-8065 5605);
PAINT MONO (-8065 5605);
FORCEPROP 1 LASTPIN (-8075 5425) $PN 2
J 0
(-8065 5405);
DISPLAY 0.787234 (-8065 5405);
PAINT MONO (-8065 5405);
FORCEPROP 1 LAST TOLERANCE 20%
J 0
(-8025 5475);
DISPLAY 0.638298 (-8025 5475);
FORCEPROP 1 LAST PACK_TYPE C0402
J 0
(-8025 5325);
DISPLAY 0.638298 (-8025 5325);
FORCEPROP 1 LAST VALUE 10UF
J 0
(-8025 5575);
DISPLAY 0.638298 (-8025 5575);
FORCEPROP 1 LAST VOLTAGE 6.3V
J 0
(-8025 5525);
DISPLAY 0.638298 (-8025 5525);
FORCEPROP 1 LAST MATERIAL X6S
J 0
(-8025 5425);
DISPLAY 0.638298 (-8025 5425);
FORCEPROP 2 LAST CDS_LIB pure_quanta
J 0
(-8075 5525);
DISPLAY INVISIBLE (-8075 5525);
FORCEPROP 1 LAST PATH I25
J 0
(-8025 5675);
DISPLAY 0.978723 (-8025 5675);
PAINT WHITE (-8025 5675);
DISPLAY INVISIBLE (-8025 5675);
FORCEPROP 1 LAST PART_NUMBER CH6101MEB01
J 0
(-8025 5375);
DISPLAY 0.638298 (-8025 5375);
DISPLAY INVISIBLE (-8025 5375);
FORCEADD Q_CAP..1
(-8525 5525);
FORCEPROP 1 LAST LOCATION C2512
J 0
(-8475 5625);
DISPLAY 0.638298 (-8475 5625);
FORCEPROP 0 LAST $SEC 1
J 0
(-8475 5675);
DISPLAY 0.680851 (-8475 5675);
PAINT MONO (-8475 5675);
DISPLAY INVISIBLE (-8475 5675);
FORCEPROP 0 LAST CDS_SEC 1
J 0
(-8475 5675);
DISPLAY 0.680851 (-8475 5675);
DISPLAY INVISIBLE (-8475 5675);
FORCEPROP 1 LASTPIN (-8525 5625) $PN 1
J 0
(-8515 5605);
DISPLAY 0.787234 (-8515 5605);
PAINT MONO (-8515 5605);
FORCEPROP 1 LASTPIN (-8525 5425) $PN 2
J 0
(-8515 5405);
DISPLAY 0.787234 (-8515 5405);
PAINT MONO (-8515 5405);
FORCEPROP 1 LAST PACK_TYPE C0402
J 0
(-8475 5325);
DISPLAY 0.638298 (-8475 5325);
FORCEPROP 1 LAST TOLERANCE 20%
J 0
(-8475 5475);
DISPLAY 0.638298 (-8475 5475);
FORCEPROP 1 LAST VALUE 10UF
J 0
(-8475 5575);
DISPLAY 0.638298 (-8475 5575);
FORCEPROP 1 LAST VOLTAGE 6.3V
J 0
(-8475 5525);
DISPLAY 0.638298 (-8475 5525);
FORCEPROP 1 LAST MATERIAL X6S
J 0
(-8475 5425);
DISPLAY 0.638298 (-8475 5425);
FORCEPROP 2 LAST CDS_LIB pure_quanta
J 0
(-8525 5525);
DISPLAY INVISIBLE (-8525 5525);
FORCEPROP 1 LAST PATH I26
J 0
(-8475 5675);
DISPLAY 0.978723 (-8475 5675);
PAINT WHITE (-8475 5675);
DISPLAY INVISIBLE (-8475 5675);
FORCEPROP 1 LAST PART_NUMBER CH6101MEB01
J 0
(-8475 5375);
DISPLAY 0.638298 (-8475 5375);
DISPLAY INVISIBLE (-8475 5375);
FORCEADD Q_CAP..1
(-8600 3875);
FORCEPROP 1 LAST LOCATION C2513
J 0
(-8550 3975);
DISPLAY 0.489362 (-8550 3975);
PAINT SKYBLUE (-8550 3975);
FORCEPROP 2 LAST $SEC 1
J 0
(-8550 4075);
DISPLAY 0.680851 (-8550 4075);
PAINT MONO (-8550 4075);
DISPLAY INVISIBLE (-8550 4075);
FORCEPROP 2 LAST CDS_SEC 1
J 0
(-8550 4075);
DISPLAY 1.021277 (-8550 4075);
DISPLAY INVISIBLE (-8550 4075);
FORCEPROP 1 LASTPIN (-8600 3975) $PN 1
J 0
(-8590 3955);
DISPLAY 0.489362 (-8590 3955);
FORCEPROP 1 LASTPIN (-8600 3775) $PN 2
J 0
(-8590 3755);
DISPLAY 0.489362 (-8590 3755);
FORCEPROP 1 LAST PACK_TYPE C0402
J 0
(-8550 3675);
DISPLAY 0.489362 (-8550 3675);
PAINT SKYBLUE (-8550 3675);
FORCEPROP 1 LAST VOLTAGE 4V
J 0
(-8550 3875);
DISPLAY 0.489362 (-8550 3875);
PAINT SKYBLUE (-8550 3875);
FORCEPROP 1 LAST VALUE 22UF
J 0
(-8550 3925);
DISPLAY 0.489362 (-8550 3925);
PAINT SKYBLUE (-8550 3925);
FORCEPROP 1 LAST TOLERANCE 20%
J 0
(-8550 3825);
DISPLAY 0.489362 (-8550 3825);
PAINT SKYBLUE (-8550 3825);
FORCEPROP 1 LAST MATERIAL X6S
J 0
(-8550 3775);
DISPLAY 0.489362 (-8550 3775);
PAINT SKYBLUE (-8550 3775);
FORCEPROP 2 LAST CDS_LIB pure_quanta
J 0
(-8600 3875);
PAINT MONO (-8600 3875);
DISPLAY INVISIBLE (-8600 3875);
FORCEPROP 1 LAST PATH I3
J 0
(-8550 4025);
DISPLAY 0.978723 (-8550 4025);
PAINT WHITE (-8550 4025);
DISPLAY INVISIBLE (-8550 4025);
FORCEPROP 1 LAST PART_NUMBER CH622KMEB02
J 0
(-8550 3725);
DISPLAY 0.489362 (-8550 3725);
PAINT SKYBLUE (-8550 3725);
DISPLAY INVISIBLE (-8550 3725);
FORCEADD UNIVERSAL_POWER..1
(-8600 4150);
FORCEPROP 3 LASTPIN (-8600 4100) SIG_NAME PVDD18_S5_P0\g
J 0
(-8590 4110);
DISPLAY 0.659574 (-8590 4110);
PAINT MONO (-8590 4110);
DISPLAY INVISIBLE (-8590 4110);
FORCEPROP 1 LAST HDL_POWER PVDD18_S5_P0
J 1
(-8600 4200);
DISPLAY 0.489362 (-8600 4200);
PAINT GREEN (-8600 4200);
FORCEPROP 2 LAST CDS_LIB pure_quanta_power
J 0
(-8600 4150);
DISPLAY INVISIBLE (-8600 4150);
FORCEPROP 1 LAST PATH I4
J 0
(-8550 4175);
DISPLAY 0.872340 (-8550 4175);
PAINT AQUA (-8550 4175);
DISPLAY INVISIBLE (-8550 4175);
FORCEADD UNIVERSAL_GND..1
(-8150 2750);
FORCEPROP 3 LASTPIN (-8150 2800) SIG_NAME GND\g
J 0
(-8140 2810);
DISPLAY 0.659574 (-8140 2810);
PAINT MONO (-8140 2810);
DISPLAY INVISIBLE (-8140 2810);
FORCEPROP 2 LAST CDS_LIB pure_quanta_power
J 0
(-8150 2750);
DISPLAY INVISIBLE (-8150 2750);
FORCEPROP 1 LAST HDL_POWER GND
J 1
(-8125 2675);
DISPLAY 0.872340 (-8125 2675);
PAINT GREEN (-8125 2675);
DISPLAY INVISIBLE (-8125 2675);
FORCEPROP 1 LAST PATH I7
J 0
(-8075 2750);
DISPLAY 0.872340 (-8075 2750);
PAINT AQUA (-8075 2750);
DISPLAY INVISIBLE (-8075 2750);
FORCEADD Q_CAP..1
(-8150 3100);
FORCEPROP 1 LAST LOCATION C2517
J 0
(-8100 3200);
DISPLAY 0.489362 (-8100 3200);
PAINT SKYBLUE (-8100 3200);
FORCEPROP 2 LAST $SEC 1
J 0
(-8100 3300);
DISPLAY 0.680851 (-8100 3300);
PAINT MONO (-8100 3300);
DISPLAY INVISIBLE (-8100 3300);
FORCEPROP 2 LAST CDS_SEC 1
J 0
(-8100 3300);
DISPLAY 1.021277 (-8100 3300);
DISPLAY INVISIBLE (-8100 3300);
FORCEPROP 1 LASTPIN (-8150 3200) $PN 1
J 0
(-8140 3180);
DISPLAY 0.489362 (-8140 3180);
FORCEPROP 1 LASTPIN (-8150 3000) $PN 2
J 0
(-8140 2980);
DISPLAY 0.489362 (-8140 2980);
FORCEPROP 1 LAST PACK_TYPE C0402
J 0
(-8100 2900);
DISPLAY 0.489362 (-8100 2900);
PAINT SKYBLUE (-8100 2900);
FORCEPROP 1 LAST VOLTAGE 4V
J 0
(-8100 3100);
DISPLAY 0.489362 (-8100 3100);
PAINT SKYBLUE (-8100 3100);
FORCEPROP 1 LAST VALUE 22UF
J 0
(-8100 3150);
DISPLAY 0.489362 (-8100 3150);
PAINT SKYBLUE (-8100 3150);
FORCEPROP 1 LAST TOLERANCE 20%
J 0
(-8100 3050);
DISPLAY 0.489362 (-8100 3050);
PAINT SKYBLUE (-8100 3050);
FORCEPROP 1 LAST MATERIAL X6S
J 0
(-8100 3000);
DISPLAY 0.489362 (-8100 3000);
PAINT SKYBLUE (-8100 3000);
FORCEPROP 2 LAST CDS_LIB pure_quanta
J 0
(-8150 3100);
PAINT MONO (-8150 3100);
DISPLAY INVISIBLE (-8150 3100);
FORCEPROP 1 LAST PATH I8
J 0
(-8100 3250);
DISPLAY 0.978723 (-8100 3250);
PAINT WHITE (-8100 3250);
DISPLAY INVISIBLE (-8100 3250);
FORCEPROP 1 LAST PART_NUMBER CH622KMEB02
J 0
(-8100 2950);
DISPLAY 0.489362 (-8100 2950);
PAINT SKYBLUE (-8100 2950);
DISPLAY INVISIBLE (-8100 2950);
FORCEADD Q_CAP..1
(-8150 3875);
FORCEPROP 1 LAST LOCATION C2516
J 0
(-8100 3975);
DISPLAY 0.489362 (-8100 3975);
PAINT SKYBLUE (-8100 3975);
FORCEPROP 2 LAST $SEC 1
J 0
(-8100 4075);
DISPLAY 0.680851 (-8100 4075);
PAINT MONO (-8100 4075);
DISPLAY INVISIBLE (-8100 4075);
FORCEPROP 2 LAST CDS_SEC 1
J 0
(-8100 4075);
DISPLAY 1.021277 (-8100 4075);
DISPLAY INVISIBLE (-8100 4075);
FORCEPROP 1 LASTPIN (-8150 3975) $PN 1
J 0
(-8140 3955);
DISPLAY 0.489362 (-8140 3955);
FORCEPROP 1 LASTPIN (-8150 3775) $PN 2
J 0
(-8140 3755);
DISPLAY 0.489362 (-8140 3755);
FORCEPROP 1 LAST PACK_TYPE C0402
J 0
(-8100 3675);
DISPLAY 0.489362 (-8100 3675);
PAINT SKYBLUE (-8100 3675);
FORCEPROP 1 LAST VOLTAGE 4V
J 0
(-8100 3875);
DISPLAY 0.489362 (-8100 3875);
PAINT SKYBLUE (-8100 3875);
FORCEPROP 1 LAST VALUE 22UF
J 0
(-8100 3925);
DISPLAY 0.489362 (-8100 3925);
PAINT SKYBLUE (-8100 3925);
FORCEPROP 1 LAST TOLERANCE 20%
J 0
(-8100 3825);
DISPLAY 0.489362 (-8100 3825);
PAINT SKYBLUE (-8100 3825);
FORCEPROP 1 LAST MATERIAL X6S
J 0
(-8100 3775);
DISPLAY 0.489362 (-8100 3775);
PAINT SKYBLUE (-8100 3775);
FORCEPROP 2 LAST CDS_LIB pure_quanta
J 0
(-8150 3875);
PAINT MONO (-8150 3875);
DISPLAY INVISIBLE (-8150 3875);
FORCEPROP 1 LAST PATH I9
J 0
(-8100 4025);
DISPLAY 0.978723 (-8100 4025);
PAINT WHITE (-8100 4025);
DISPLAY INVISIBLE (-8100 4025);
FORCEPROP 1 LAST PART_NUMBER CH622KMEB02
J 0
(-8100 3725);
DISPLAY 0.489362 (-8100 3725);
PAINT SKYBLUE (-8100 3725);
DISPLAY INVISIBLE (-8100 3725);
FORCEADD QUANTA_TITLE_BLOCK_C..1
(0 0);
FORCEPROP 0 LAST CDS_CON_LAST_MODIFIED Thu Sep 14 16:12:03 2023
J 0
(-1885 15);
DISPLAY INVISIBLE (-1885 15);
FORCEPROP 1 LAST CUSTOM_TXT_CDS <CON_LAST_MODIFIED>
J 0
(-1885 15);
DISPLAY 0.978723 (-1885 15);
FORCEPROP 2 LAST CUSTOM_TXT_CDS <XR_PAGE_TITLE>
J 0
(-7890 5250);
DISPLAY 0.638298 (-7890 5250);
PAINT PINK (-7890 5250);
DISPLAY INVISIBLE (-7890 5250);
FORCEPROP 1 LAST CUSTOM_TXT_CDS <NAME_2>
J 0
(-3175 50);
FORCEPROP 1 LAST CUSTOM_TXT_CDS <NAME_1>
J 0
(-3175 175);
FORCEPROP 1 LAST CUSTOM_TXT_CDS <Q_NUMBER>
J 0
(-1403 103);
DISPLAY 1.212766 (-1403 103);
FORCEPROP 1 LAST CUSTOM_TXT_CDS <Q_PROJ>
J 0
(-2382 102);
DISPLAY 1.212766 (-2382 102);
FORCEPROP 1 LAST CUSTOM_TXT_CDS <Q_REV>
J 0
(-184 103);
DISPLAY 1.212766 (-184 103);
FORCEPROP 1 LAST CUSTOM_TXT_CDS <CON_PAGE_NUM> OF <CON_TOTAL_PAGES>
J 0
(-446 18);
DISPLAY 0.978723 (-446 18);
FORCEPROP 1 LAST Q_TITLE CPU0 CAVITY BOT DECOUPLING CAPS 3/3
J 0
(-9366 26);
DISPLAY 2.446809 (-9366 26);
PAINT GREEN (-9366 26);
FORCEPROP 1 LAST CDS_LMAN_SYM_OUTLINE -9475,6775,100,-125
J 0
(0 0);
DISPLAY 0.468085 (0 0);
PAINT GREEN (0 0);
DISPLAY INVISIBLE (0 0);
FORCEPROP 2 LAST CDS_LIB pure_quanta
J 0
(0 0);
DISPLAY INVISIBLE (0 0);
FORCEPROP 2 LAST PAGE_BORDER TRUE
J 0
(-7890 5250);
DISPLAY 0.638298 (-7890 5250);
PAINT PINK (-7890 5250);
DISPLAY INVISIBLE (-7890 5250);
FORCEPROP 2 LAST CDS_XR_PAGE_TITLE CR-71 : @T6G_MB_LIB.T6G(SCH_1):PAGE71
J 0
(-7890 5250);
DISPLAY 0.638298 (-7890 5250);
PAINT PINK (-7890 5250);
DISPLAY INVISIBLE (-7890 5250);
FORCEPROP 1 LAST Q_DEPT BU9
J 1
(-3763 49);
DISPLAY 1.957447 (-3763 49);
PAINT GREEN (-3763 49);
DISPLAY INVISIBLE (-3763 49);
FORCEPROP 1 LAST COMMENT_BODY TRUE
J 0
(12 -13);
DISPLAY 0.978723 (12 -13);
PAINT GREEN (12 -13);
DISPLAY INVISIBLE (12 -13);
WIRE 16 -1 (-8075 5625)(-8075 5700);
WIRE 16 -1 (-8075 5700)(-8525 5700);
WIRE 16 -1 (-8525 5700)(-8525 5750);
WIRE 16 -1 (-8525 5700)(-8525 5625);
WIRE 16 -1 (-8075 5300)(-8075 5425);
WIRE 16 -1 (-8075 5200)(-8075 5300);
WIRE 16 -1 (-8075 5300)(-8525 5300);
WIRE 16 -1 (-8525 5300)(-8525 5425);
WIRE 16 3135 (-8825 6275)(-4900 6275);
WIRE 16 3135 (-8825 5000)(-8825 6275);
WIRE 16 3135 (-4900 5000)(-4900 6275);
WIRE 16 3135 (-8825 5000)(-4900 5000);
WIRE 16 3135 (-8825 2575)(-4075 2575);
WIRE 16 3135 (-8825 2575)(-8825 4700);
WIRE 16 3135 (-4075 2575)(-4075 4700);
WIRE 16 3135 (-8825 4700)(-4075 4700);
WIRE 16 -1 (-7700 3650)(-8150 3650);
WIRE 16 -1 (-7250 3650)(-7700 3650);
WIRE 16 -1 (-7700 3650)(-7700 3775);
WIRE 16 -1 (-8150 3650)(-8150 3775);
WIRE 16 -1 (-8150 3650)(-8600 3650);
WIRE 16 -1 (-8600 3650)(-8600 3775);
WIRE 16 -1 (-6800 3650)(-7250 3650);
WIRE 16 -1 (-7250 3650)(-7250 3775);
WIRE 16 -1 (-6350 3650)(-6800 3650);
WIRE 16 -1 (-6800 3650)(-6800 3775);
WIRE 16 -1 (-5900 3650)(-6350 3650);
WIRE 16 -1 (-6350 3650)(-6350 3775);
WIRE 16 -1 (-5450 3650)(-5900 3650);
WIRE 16 -1 (-5900 3650)(-5900 3775);
WIRE 16 -1 (-5000 3650)(-5450 3650);
WIRE 16 -1 (-5450 3650)(-5450 3775);
WIRE 16 -1 (-4600 3650)(-5000 3650);
WIRE 16 -1 (-5000 3650)(-5000 3775);
WIRE 16 -1 (-4600 3650)(-4600 3775);
WIRE 16 -1 (-4600 3550)(-4600 3650);
WIRE 16 -1 (-8150 3200)(-8150 3275);
WIRE 16 -1 (-8150 3275)(-8600 3275);
WIRE 16 -1 (-8600 3275)(-8600 3200);
WIRE 16 -1 (-8600 3275)(-8600 3325);
WIRE 16 -1 (-7250 4050)(-7700 4050);
WIRE 16 -1 (-6800 4050)(-7250 4050);
WIRE 16 -1 (-7250 3975)(-7250 4050);
WIRE 16 -1 (-7700 4050)(-7700 3975);
WIRE 16 -1 (-7700 4050)(-8150 4050);
WIRE 16 -1 (-8150 3975)(-8150 4050);
WIRE 16 -1 (-8150 4050)(-8600 4050);
WIRE 16 -1 (-6350 4050)(-6800 4050);
WIRE 16 -1 (-6800 3975)(-6800 4050);
WIRE 16 -1 (-5900 4050)(-6350 4050);
WIRE 16 -1 (-6350 4050)(-6350 3975);
WIRE 16 -1 (-8600 4050)(-8600 4100);
WIRE 16 -1 (-8600 4050)(-8600 3975);
WIRE 16 -1 (-5450 4050)(-5900 4050);
WIRE 16 -1 (-5900 3975)(-5900 4050);
WIRE 16 -1 (-5000 4050)(-5450 4050);
WIRE 16 -1 (-5450 3975)(-5450 4050);
WIRE 16 -1 (-4600 4050)(-5000 4050);
WIRE 16 -1 (-5000 4050)(-5000 3975);
WIRE 16 -1 (-4600 3975)(-4600 4050);
WIRE 16 -1 (-8150 2875)(-8150 3000);
WIRE 16 -1 (-8150 2800)(-8150 2875);
WIRE 16 -1 (-8150 2875)(-8600 2875);
WIRE 16 -1 (-8600 2875)(-8600 3000);
DOT 1 (-8525 5700);
DOT 1 (-8075 5300);
DOT 1 (-4600 3650);
DOT 1 (-5000 4050);
DOT 1 (-5000 3650);
DOT 1 (-5450 4050);
DOT 1 (-5450 3650);
DOT 1 (-5900 4050);
DOT 1 (-5900 3650);
DOT 1 (-6350 4050);
DOT 1 (-6350 3650);
DOT 1 (-6800 4050);
DOT 1 (-6800 3650);
DOT 1 (-7250 4050);
DOT 1 (-7250 3650);
DOT 1 (-7700 4050);
DOT 1 (-7700 3650);
DOT 1 (-8150 4050);
DOT 1 (-8150 3650);
DOT 1 (-8150 2875);
DOT 1 (-8600 4050);
DOT 1 (-8600 3275);
FORCENOTE
PVDD18_S5_P0: 12PCS 22UF ON BOT
(-8675 4475) 0;
DISPLAY LEFT (-8675 4475);
DISPLAY 2.510638 (-8675 4475);
PAINT WHITE (-8675 4475);
FORCENOTE
PVDD33_S5: 2PCS 22UF ON BOT
(-8625 6000) 0;
DISPLAY LEFT (-8625 6000);
DISPLAY 2.510638 (-8625 6000);
PAINT WHITE (-8625 6000);
FORCENOTE
10
(-4650 4125) 0;
DISPLAY LEFT (-4650 4125);
DISPLAY 1.021277 (-4650 4125);
PAINT SKYBLUE (-4650 4125);
FORCENOTE
5
(-6825 4125) 0;
DISPLAY LEFT (-6825 4125);
DISPLAY 1.021277 (-6825 4125);
PAINT SKYBLUE (-6825 4125);
QUIT
